(kicad_pcb
	(version 20260206)
	(generator "pcbnew")
	(generator_version "10.0")
	(general
		(thickness 1.6)
		(legacy_teardrops no)
	)
	(paper "A4")
	(title_block
		(title "Bryce Canyon_F.DPB_16315-1-OCP.brd")
		(comment 1 "Bryce Canyon / footprints 1970-1972 of 2223")
	)
	(layers
		(0 "F.Cu" signal "TOP")
		(4 "In1.Cu" signal "L2GND")
		(6 "In2.Cu" signal "L3")
		(8 "In3.Cu" signal "L4GND")
		(10 "In4.Cu" signal "L5")
		(12 "In5.Cu" signal "L6VCC")
		(14 "In6.Cu" signal "L7VCC")
		(16 "In7.Cu" signal "L8")
		(18 "In8.Cu" signal "L9GND")
		(20 "In9.Cu" signal "L10")
		(22 "In10.Cu" signal "L11GND")
		(2 "B.Cu" signal "BOTTOM")
		(9 "F.Adhes" user "F.Adhesive")
		(11 "B.Adhes" user "B.Adhesive")
		(13 "F.Paste" user "Package Geometry/Pastemask Top")
		(15 "B.Paste" user "Package Geometry/Pastemask Bottom")
		(5 "F.SilkS" user "Ref Des/Silkscreen Top")
		(7 "B.SilkS" user "Ref Des/Silkscreen Bottom")
		(1 "F.Mask" user "Board Geometry/Soldermask Top")
		(3 "B.Mask" user "Board Geometry/Soldermask Bottom")
		(17 "Dwgs.User" user "User.Drawings")
		(19 "Cmts.User" user "User.Comments")
		(21 "Eco1.User" user "User.Eco1")
		(23 "Eco2.User" user "User.Eco2")
		(25 "Edge.Cuts" user "Board Geometry/Outline")
		(27 "Margin" user)
		(31 "F.CrtYd" user "Package Geometry/Place Bound Top")
		(29 "B.CrtYd" user "Package Geometry/Place Bound Bottom")
		(35 "F.Fab" user "Ref Des/Assembly Top")
		(33 "B.Fab" user "Ref Des/Assembly Bottom")
	)
	(footprint ""
		(layer "F.Cu")
		(at 420.200074 -172.909992 -90)
		(property "Reference" "HDDSAS21"
			(at 0 0 270)
			(layer "F.SilkS")
			(hide yes)
			(effects
				(font
					(size 1.27 1.27)
				)
			)
		)
		(property "Value" "SKT-SAS15P-14P-45-GP"
			(at -20.7645 -8.9789 270)
			(unlocked yes)
			(layer "F.Fab")
			(hide yes)
			(effects
				(font
					(size 1.016 1.016)
					(thickness 0.1524)
				)
			)
		)
		(property "Device Type" "10120818-001C-TRLF"
			(at -20.7645 -10.5029 270)
			(unlocked yes)
			(layer "F.Fab")
			(hide yes)
			(effects
				(font
					(size 1.016 1.016)
					(thickness 0.1524)
				)
			)
		)
		(duplicate_pad_numbers_are_jumpers no)
		(fp_line
			(start 1.651 4.2926)
			(end 1.651 3.0099)
			(stroke
				(width 0.1524)
				(type default)
			)
			(layer "F.SilkS")
		)
		(fp_line
			(start 8.509 4.2926)
			(end 1.651 4.2926)
			(stroke
				(width 0.1524)
				(type default)
			)
			(layer "F.SilkS")
		)
		(fp_line
			(start -23.4188 3.0099)
			(end -23.4188 -3.2512)
			(stroke
				(width 0.1524)
				(type default)
			)
			(layer "F.SilkS")
		)
		(fp_line
			(start 1.651 3.0099)
			(end -23.4188 3.0099)
			(stroke
				(width 0.1524)
				(type default)
			)
			(layer "F.SilkS")
		)
		(fp_line
			(start 8.509 3.0099)
			(end 8.509 4.2926)
			(stroke
				(width 0.1524)
				(type default)
			)
			(layer "F.SilkS")
		)
		(fp_line
			(start 23.4188 3.0099)
			(end 8.509 3.0099)
			(stroke
				(width 0.1524)
				(type default)
			)
			(layer "F.SilkS")
		)
		(fp_line
			(start -23.4188 -3.2512)
			(end 23.4188 -3.2512)
			(stroke
				(width 0.1524)
				(type default)
			)
			(layer "F.SilkS")
		)
		(fp_line
			(start 23.4188 -3.2512)
			(end 23.4188 3.0099)
			(stroke
				(width 0.1524)
				(type default)
			)
			(layer "F.SilkS")
		)
		(fp_line
			(start 15.5067 -3.3401)
			(end 16.2687 -3.3401)
			(stroke
				(width 0.3302)
				(type default)
			)
			(layer "F.SilkS")
		)
		(fp_poly
			(pts
				(xy 15.868904 -3.230372) (xy 16.503904 -3.865372) (xy 15.233904 -3.865372)
			)
			(stroke
				(width 0)
				(type default)
			)
			(fill yes)
			(layer "F.SilkS")
		)
		(fp_poly
			(pts
				(xy -22.8727 -2.7559) (xy 22.8727 -2.7559) (xy 22.8727 2.7559) (xy 8.255 2.7559) (xy 8.255 3.5179)
				(xy 1.905 3.5179) (xy 1.905 2.7559) (xy -22.8727 2.7559)
			)
			(stroke
				(width 0)
				(type default)
			)
			(fill no)
			(layer "F.CrtYd")
		)
		(fp_poly
			(pts
				(xy 1.397 4.5466) (xy 1.397 3.2639) (xy -23.6728 3.2639) (xy -23.6728 -3.5052) (xy 23.6728 -3.5052)
				(xy 23.6728 -0.00635) (xy 22.8727 -0.00635) (xy 22.8727 -2.7559) (xy -22.8727 -2.7559) (xy -22.8727 2.7559)
				(xy 1.905 2.7559) (xy 1.905 3.5179) (xy 8.255 3.5179) (xy 8.255 2.7559) (xy 22.8727 2.7559) (xy 22.8727 0.00635)
				(xy 23.6728 0.00635) (xy 23.6728 3.2639) (xy 8.763 3.2639) (xy 8.763 4.5466)
			)
			(stroke
				(width 0)
				(type default)
			)
			(fill no)
			(layer "F.CrtYd")
		)
		(fp_poly
			(pts
				(xy 1.397 4.5466) (xy 1.397 3.2639) (xy -23.6728 3.2639) (xy -23.6728 -3.5052) (xy 23.6728 -3.5052)
				(xy 23.6728 3.2639) (xy 8.763 3.2639) (xy 8.763 4.5466)
			)
			(stroke
				(width 0)
				(type default)
			)
			(fill no)
			(layer "F.Fab")
		)
		(pad "" np_thru_hole circle
			(at -18.874994 0 270)
			(size 0.254 0.254)
			(drill 1.3462)
			(layers "*.Cu" "*.Mask")
			(clearance 0.9017)
			(thermal_gap 0.9017)
		)
		(pad "" np_thru_hole circle
			(at 18.874994 0 270)
			(size 0.254 0.254)
			(drill 0.9398)
			(layers "*.Cu" "*.Mask")
			(clearance 0.6985)
			(thermal_gap 0.6985)
		)
		(pad "G1" smd rect
			(at 21.874988 0 270)
			(size 2.5908 2.5908)
			(layers "F.Cu" "F.Mask" "F.Paste")
			(net "GND")
		)
		(pad "G2" smd rect
			(at -21.874988 0 270)
			(size 2.5908 2.5908)
			(layers "F.Cu" "F.Mask" "F.Paste")
			(net "GND")
		)
		(pad "P1" smd rect
			(at 1.905 -1.82499 270)
			(size 0.6096 2.3622)
			(layers "F.Cu" "F.Mask" "F.Paste")
			(net "Net_2106")
		)
		(pad "P2" smd rect
			(at 0.635 -1.82499 270)
			(size 0.6096 2.3622)
			(layers "F.Cu" "F.Mask" "F.Paste")
			(net "Net_2107")
		)
		(pad "P3" smd rect
			(at -0.635 -1.82499 270)
			(size 0.6096 2.3622)
			(layers "F.Cu" "F.Mask" "F.Paste")
			(net "Net_2108")
		)
		(pad "P4" smd rect
			(at -1.905 -1.82499 270)
			(size 0.6096 2.3622)
			(layers "F.Cu" "F.Mask" "F.Paste")
			(net "GND")
		)
		(pad "P5" smd rect
			(at -3.175 -1.82499 270)
			(size 0.6096 2.3622)
			(layers "F.Cu" "F.Mask" "F.Paste")
			(net "HDD_PRSNT_21")
		)
		(pad "P6" smd rect
			(at -4.445 -1.82499 270)
			(size 0.6096 2.3622)
			(layers "F.Cu" "F.Mask" "F.Paste")
			(net "GND")
		)
		(pad "P7" smd rect
			(at -5.715 -1.82499 270)
			(size 0.6096 2.3622)
			(layers "F.Cu" "F.Mask" "F.Paste")
			(net "5V_PRE_21")
		)
		(pad "P8" smd rect
			(at -6.985 -1.82499 270)
			(size 0.6096 2.3622)
			(layers "F.Cu" "F.Mask" "F.Paste")
			(net "P5V_HDD21")
		)
		(pad "P9" smd rect
			(at -8.255 -1.82499 270)
			(size 0.6096 2.3622)
			(layers "F.Cu" "F.Mask" "F.Paste")
			(net "P5V_HDD21")
		)
		(pad "P10" smd rect
			(at -9.525 -1.82499 270)
			(size 0.6096 2.3622)
			(layers "F.Cu" "F.Mask" "F.Paste")
			(net "GND")
		)
		(pad "P11" smd rect
			(at -10.795 -1.82499 270)
			(size 0.6096 2.3622)
			(layers "F.Cu" "F.Mask" "F.Paste")
			(net "ACT_HDD_21")
		)
		(pad "P12" smd rect
			(at -12.065 -1.82499 270)
			(size 0.6096 2.3622)
			(layers "F.Cu" "F.Mask" "F.Paste")
			(net "GND")
		)
		(pad "P13" smd rect
			(at -13.335 -1.82499 270)
			(size 0.6096 2.3622)
			(layers "F.Cu" "F.Mask" "F.Paste")
			(net "12V_PRE_21")
		)
		(pad "P14" smd rect
			(at -14.605 -1.82499 270)
			(size 0.6096 2.3622)
			(layers "F.Cu" "F.Mask" "F.Paste")
			(net "P12V_HDD21")
		)
		(pad "P15" smd rect
			(at -15.875 -1.82499 270)
			(size 0.6096 2.3622)
			(layers "F.Cu" "F.Mask" "F.Paste")
			(net "P12V_HDD21")
		)
		(pad "S1" smd rect
			(at 15.875 -1.82499 270)
			(size 0.6096 2.3622)
			(layers "F.Cu" "F.Mask" "F.Paste")
			(net "GND")
		)
		(pad "S2" smd rect
			(at 14.605 -1.82499 270)
			(size 0.6096 2.3622)
			(layers "F.Cu" "F.Mask" "F.Paste")
			(net "SAS_HDD_RX_P21")
		)
		(pad "S3" smd rect
			(at 13.335 -1.82499 270)
			(size 0.6096 2.3622)
			(layers "F.Cu" "F.Mask" "F.Paste")
			(net "SAS_HDD_RX_N21")
		)
		(pad "S4" smd rect
			(at 12.065 -1.82499 270)
			(size 0.6096 2.3622)
			(layers "F.Cu" "F.Mask" "F.Paste")
			(net "GND")
		)
		(pad "S5" smd rect
			(at 10.795 -1.82499 270)
			(size 0.6096 2.3622)
			(layers "F.Cu" "F.Mask" "F.Paste")
			(net "PHY_DRV_A_TO_SCC_A_21_DN")
		)
		(pad "S6" smd rect
			(at 9.525 -1.82499 270)
			(size 0.6096 2.3622)
			(layers "F.Cu" "F.Mask" "F.Paste")
			(net "PHY_DRV_A_TO_SCC_A_21_DP")
		)
		(pad "S7" smd rect
			(at 8.255 -1.82499 270)
			(size 0.6096 2.3622)
			(layers "F.Cu" "F.Mask" "F.Paste")
			(net "GND")
		)
		(pad "S8" smd rect
			(at 7.480046 2.845054 270)
			(size 0.508 2.3622)
			(layers "F.Cu" "F.Mask" "F.Paste")
			(net "GND")
		)
		(pad "S9" smd rect
			(at 6.679946 2.845054 270)
			(size 0.508 2.3622)
			(layers "F.Cu" "F.Mask" "F.Paste")
			(net "Net_459")
		)
		(pad "S10" smd rect
			(at 5.8801 2.845054 270)
			(size 0.508 2.3622)
			(layers "F.Cu" "F.Mask" "F.Paste")
			(net "Net_351")
		)
		(pad "S11" smd rect
			(at 5.08 2.845054 270)
			(size 0.508 2.3622)
			(layers "F.Cu" "F.Mask" "F.Paste")
			(net "GND")
		)
		(pad "S12" smd rect
			(at 4.2799 2.845054 270)
			(size 0.508 2.3622)
			(layers "F.Cu" "F.Mask" "F.Paste")
			(net "Net_387")
		)
		(pad "S13" smd rect
			(at 3.480054 2.845054 270)
			(size 0.508 2.3622)
			(layers "F.Cu" "F.Mask" "F.Paste")
			(net "Net_423")
		)
		(pad "S14" smd rect
			(at 2.679954 2.845054 270)
			(size 0.508 2.3622)
			(layers "F.Cu" "F.Mask" "F.Paste")
			(net "GND")
		)
		(zone
			(layer "F.Cu")
			(hatch none 0.5)
			(connect_pads
				(clearance 0)
			)
			(min_thickness 0.25)
			(keepout
				(tracks allowed)
				(vias not_allowed)
				(pads allowed)
				(copperpour not_allowed)
				(footprints allowed)
			)
			(placement
				(enabled no)
				(sheetname "")
			)
			(fill
				(thermal_gap 0.5)
				(thermal_bridge_width 0.5)
				(island_removal_mode 0)
			)
			(polygon
				(pts
					(xy 423.857674 -189.648592) (xy 416.783774 -189.648592) (xy 416.783774 -196.582792) (xy 417.888674 -196.582792)
					(xy 417.888674 -192.467992) (xy 422.511474 -192.467992) (xy 422.511474 -196.582792) (xy 423.857674 -196.582792)
				)
			)
		)
		(zone
			(layer "F.Cu")
			(hatch none 0.5)
			(connect_pads
				(clearance 0)
			)
			(min_thickness 0.25)
			(keepout
				(tracks not_allowed)
				(vias allowed)
				(pads allowed)
				(copperpour not_allowed)
				(footprints allowed)
			)
			(placement
				(enabled no)
				(sheetname "")
			)
			(fill
				(thermal_gap 0.5)
				(thermal_bridge_width 0.5)
				(island_removal_mode 0)
			)
			(polygon
				(pts
					(xy 423.857674 -189.648592) (xy 416.783774 -189.648592) (xy 416.783774 -196.582792) (xy 417.888674 -196.582792)
					(xy 417.888674 -192.467992) (xy 422.511474 -192.467992) (xy 422.511474 -196.582792) (xy 423.857674 -196.582792)
				)
			)
		)
		(zone
			(layer "F.Cu")
			(hatch none 0.5)
			(connect_pads
				(clearance 0)
			)
			(min_thickness 0.25)
			(keepout
				(tracks allowed)
				(vias not_allowed)
				(pads allowed)
				(copperpour not_allowed)
				(footprints allowed)
			)
			(placement
				(enabled no)
				(sheetname "")
			)
			(fill
				(thermal_gap 0.5)
				(thermal_bridge_width 0.5)
				(island_removal_mode 0)
			)
			(polygon
				(pts
					(xy 423.857674 -156.171392) (xy 416.783774 -156.171392) (xy 416.783774 -149.237192) (xy 417.888674 -149.237192)
					(xy 417.888674 -153.351992) (xy 422.511474 -153.351992) (xy 422.511474 -149.237192) (xy 423.857674 -149.237192)
				)
			)
		)
		(zone
			(layer "F.Cu")
			(hatch none 0.5)
			(connect_pads
				(clearance 0)
			)
			(min_thickness 0.25)
			(keepout
				(tracks not_allowed)
				(vias allowed)
				(pads allowed)
				(copperpour not_allowed)
				(footprints allowed)
			)
			(placement
				(enabled no)
				(sheetname "")
			)
			(fill
				(thermal_gap 0.5)
				(thermal_bridge_width 0.5)
				(island_removal_mode 0)
			)
			(polygon
				(pts
					(xy 423.857674 -156.171392) (xy 416.783774 -156.171392) (xy 416.783774 -149.237192) (xy 417.888674 -149.237192)
					(xy 417.888674 -153.351992) (xy 422.511474 -153.351992) (xy 422.511474 -149.237192) (xy 423.857674 -149.237192)
				)
			)
		)
		(zone
			(layers "F.Cu" "B.Cu" "In1.Cu" "In2.Cu" "In3.Cu" "In4.Cu" "In5.Cu" "In6.Cu"
				"In7.Cu" "In8.Cu" "In9.Cu" "In10.Cu"
			)
			(hatch none 0.5)
			(connect_pads
				(clearance 0)
			)
			(min_thickness 0.25)
			(keepout
				(tracks not_allowed)
				(vias allowed)
				(pads allowed)
				(copperpour not_allowed)
				(footprints allowed)
			)
			(placement
				(enabled no)
				(sheetname "")
			)
			(fill
				(thermal_gap 0.5)
				(thermal_bridge_width 0.5)
				(island_removal_mode 0)
			)
			(polygon
				(pts
					(arc
						(start 420.974774 -154.034998)
						(mid 419.425374 -154.034998)
						(end 420.974774 -154.034998)
					)
				)
			)
		)
		(zone
			(layers "F.Cu" "B.Cu" "In1.Cu" "In2.Cu" "In3.Cu" "In4.Cu" "In5.Cu" "In6.Cu"
				"In7.Cu" "In8.Cu" "In9.Cu" "In10.Cu"
			)
			(hatch none 0.5)
			(connect_pads
				(clearance 0)
			)
			(min_thickness 0.25)
			(keepout
				(tracks not_allowed)
				(vias allowed)
				(pads allowed)
				(copperpour not_allowed)
				(footprints allowed)
			)
			(placement
				(enabled no)
				(sheetname "")
			)
			(fill
				(thermal_gap 0.5)
				(thermal_bridge_width 0.5)
				(island_removal_mode 0)
			)
			(polygon
				(pts
					(arc
						(start 421.177974 -191.784986)
						(mid 419.222174 -191.784986)
						(end 421.177974 -191.784986)
					)
				)
			)
		)
	)
	(footprint ""
		(layer "F.Cu")
		(at 117.646196 -44.821094 -90)
		(property "Reference" "R761"
			(at 0 0 270)
			(layer "F.SilkS")
			(hide yes)
			(effects
				(font
					(size 1.27 1.27)
				)
			)
		)
		(property "Value" "0R2J-2-GP"
			(at 0.064008 -3.993896 270)
			(unlocked yes)
			(layer "F.Fab")
			(hide yes)
			(effects
				(font
					(size 1.016 1.016)
					(thickness 0.1524)
				)
			)
		)
		(property "Device Type" "R402H16"
			(at 0.064008 -5.517896 270)
			(unlocked yes)
			(layer "F.Fab")
			(hide yes)
			(effects
				(font
					(size 1.016 1.016)
					(thickness 0.1524)
				)
			)
		)
		(duplicate_pad_numbers_are_jumpers no)
		(fp_line
			(start -0.508 -0.9398)
			(end -0.508 0.9398)
			(stroke
				(width 0.1524)
				(type default)
			)
			(layer "F.SilkS")
		)
		(fp_line
			(start 0.508 -0.9398)
			(end -0.508 -0.9398)
			(stroke
				(width 0.1524)
				(type default)
			)
			(layer "F.SilkS")
		)
		(fp_rect
			(start -0.508 0.9398)
			(end 0.508 -0.9398)
			(stroke
				(width 0)
				(type default)
			)
			(fill no)
			(layer "F.CrtYd")
		)
		(fp_rect
			(start -0.508 0.9398)
			(end 0.508 -0.9398)
			(stroke
				(width 0)
				(type default)
			)
			(fill no)
			(layer "F.Fab")
		)
		(pad "1" smd custom
			(at 0 -0.4445 270)
			(size 0.1397 0.1397)
			(layers "F.Cu" "F.Mask" "F.Paste")
			(net "DRIVE_A_27_PWR")
			(options
				(clearance outline)
				(anchor circle)
			)
			(primitives
				(gr_poly
					(pts
						(arc
							(start -0.1778 -0.2794)
							(mid -0.249642 -0.249642)
							(end -0.2794 -0.1778)
						)
						(arc
							(start -0.2794 0.1778)
							(mid -0.249642 0.249642)
							(end -0.1778 0.2794)
						)
						(arc
							(start 0.1778 0.2794)
							(mid 0.249642 0.249642)
							(end 0.2794 0.1778)
						)
						(arc
							(start 0.2794 -0.1778)
							(mid 0.249642 -0.249642)
							(end 0.1778 -0.2794)
						)
					)
					(width 0)
					(fill yes)
				)
			)
		)
		(pad "2" smd custom
			(at 0 0.4445 270)
			(size 0.1397 0.1397)
			(layers "F.Cu" "F.Mask" "F.Paste")
			(net "SW_PWR_R_HDD27")
			(options
				(clearance outline)
				(anchor circle)
			)
			(primitives
				(gr_poly
					(pts
						(arc
							(start -0.1778 -0.2794)
							(mid -0.249642 -0.249642)
							(end -0.2794 -0.1778)
						)
						(arc
							(start -0.2794 0.1778)
							(mid -0.249642 0.249642)
							(end -0.1778 0.2794)
						)
						(arc
							(start 0.1778 0.2794)
							(mid 0.249642 0.249642)
							(end 0.2794 0.1778)
						)
						(arc
							(start 0.2794 -0.1778)
							(mid 0.249642 -0.249642)
							(end 0.1778 -0.2794)
						)
					)
					(width 0)
					(fill yes)
				)
			)
		)
	)
	(footprint ""
		(layer "F.Cu")
		(at 243.713 -249.174)
		(property "Reference" "R50"
			(at 0 0 0)
			(layer "F.SilkS")
			(hide yes)
			(effects
				(font
					(size 1.27 1.27)
				)
			)
		)
		(property "Value" "4K7R2F-GP"
			(at 0.064008 -3.993896 0)
			(unlocked yes)
			(layer "F.Fab")
			(hide yes)
			(effects
				(font
					(size 1.016 1.016)
					(thickness 0.1524)
				)
			)
		)
		(property "Device Type" "R402H16"
			(at 0.064008 -5.517896 0)
			(unlocked yes)
			(layer "F.Fab")
			(hide yes)
			(effects
				(font
					(size 1.016 1.016)
					(thickness 0.1524)
				)
			)
		)
		(duplicate_pad_numbers_are_jumpers no)
		(fp_line
			(start -0.508 -0.9398)
			(end -0.508 0.9398)
			(stroke
				(width 0.1524)
				(type default)
			)
			(layer "F.SilkS")
		)
		(fp_line
			(start 0.508 -0.9398)
			(end -0.508 -0.9398)
			(stroke
				(width 0.1524)
				(type default)
			)
			(layer "F.SilkS")
		)
		(fp_rect
			(start -0.508 0.9398)
			(end 0.508 -0.9398)
			(stroke
				(width 0)
				(type default)
			)
			(fill no)
			(layer "F.CrtYd")
		)
		(fp_rect
			(start -0.508 0.9398)
			(end 0.508 -0.9398)
			(stroke
				(width 0)
				(type default)
			)
			(fill no)
			(layer "F.Fab")
		)
		(pad "1" smd custom
			(at 0 -0.4445)
			(size 0.1397 0.1397)
			(layers "F.Cu" "F.Mask" "F.Paste")
			(net "IO_EXP5_A2")
			(options
				(clearance outline)
				(anchor circle)
			)
			(primitives
				(gr_poly
					(pts
						(arc
							(start -0.1778 -0.2794)
							(mid -0.249642 -0.249642)
							(end -0.2794 -0.1778)
						)
						(arc
							(start -0.2794 0.1778)
							(mid -0.249642 0.249642)
							(end -0.1778 0.2794)
						)
						(arc
							(start 0.1778 0.2794)
							(mid 0.249642 0.249642)
							(end 0.2794 0.1778)
						)
						(arc
							(start 0.2794 -0.1778)
							(mid 0.249642 -0.249642)
							(end 0.1778 -0.2794)
						)
					)
					(width 0)
					(fill yes)
				)
			)
		)
		(pad "2" smd custom
			(at 0 0.4445)
			(size 0.1397 0.1397)
			(layers "F.Cu" "F.Mask" "F.Paste")
			(net "GND")
			(options
				(clearance outline)
				(anchor circle)
			)
			(primitives
				(gr_poly
					(pts
						(arc
							(start -0.1778 -0.2794)
							(mid -0.249642 -0.249642)
							(end -0.2794 -0.1778)
						)
						(arc
							(start -0.2794 0.1778)
							(mid -0.249642 0.249642)
							(end -0.1778 0.2794)
						)
						(arc
							(start 0.1778 0.2794)
							(mid 0.249642 0.249642)
							(end 0.2794 0.1778)
						)
						(arc
							(start 0.2794 -0.1778)
							(mid 0.249642 -0.249642)
							(end 0.1778 -0.2794)
						)
					)
					(width 0)
					(fill yes)
				)
			)
		)
	)
)
